FILE_TYPE = CONNECTIVITY;
{Allegro Design Entry HDL 16.6-p007 (v16-6-112F) 10/10/2012}
"PAGE_NUMBER" = 38;
0"NC";
1"PVDDQ_ABC\g";
2"PVDDQ_DEF\g";
3"PVCCIO_CPU0\g";
4"GND\g";
5"PVCCIO_CPU0\g";
6"PVSA_CPU0\g";
7"PVCCIOMCP_CPU0\g";
8"PVCCMCP_CPU0\g";
9"PVPP_ABC\g";
10"P1V8_MCP_CPU0\g";
11"P3V3_STBY\g";
%"PVDDQ_ABC"
"1","(-3075,4400)","0","mstr_symbols","I11";
;
HDL_POWER"PVDDQ_ABC"
BODY_TYPE"PLUMBING"
CDS_LIB"mstr_symbols"
VOLTAGE"1.2V";
"G\NAC"1;
%"PVDDQ_DEF"
"1","(-800,4400)","0","mstr_symbols","I12";
;
HDL_POWER"PVDDQ_DEF"
BODY_TYPE"PLUMBING"
CDS_LIB"mstr_symbols"
VOLTAGE"1.2V";
"G\NAC"2;
%"PVCCIO_CPU0"
"1","(-250,4875)","0","mstr_symbols","I14";
;
HDL_POWER"PVCCIO_CPU0"
BODY_TYPE"PLUMBING"
CDS_LIB"mstr_symbols"
VOLTAGE"1.1V";
"G\NAC"3;
%"GND"
"1","(3400,850)","0","mstr_symbols","I16";
;
HDL_POWER"GND"
BODY_TYPE"PLUMBING"
SIZE"1B"
CDS_LIB"mstr_symbols"
VOLTAGE"0.0V";
"A\NAC"4;
%"PVCCIO_CPU0"
"1","(2900,1225)","0","mstr_symbols","I17";
;
HDL_POWER"PVCCIO_CPU0"
BODY_TYPE"PLUMBING"
CDS_LIB"mstr_symbols"
VOLTAGE"1.1V";
"G\NAC"5;
%"CAP"
"1","(3400,1125)","0","mstr_discrete","I19";
;
CDS_SEC"1"
ROOM"CPU0"
CDS_LOCATION"C6D1"
SEC"1"
BOM_COST"PROC_SOCKET"
SEC_TYPE"0603LF"
CDS_LIB"mstr_discrete"
MATERIAL"X6S"
VOLTAGE"4V"
PACK_TYPE"0603LF"
TOLERANCE"20%"
VALUE"10UF"
PART_NUMBER"E15431-001"
LOCATION"C6D1";
"A"
$PN"1"10;
"B"
$PN"2"4;
%"PVSA_CPU0"
"1","(2150,4950)","0","mstr_symbols","I24";
;
HDL_POWER"PVSA_CPU0"
BODY_TYPE"PLUMBING"
CDS_LIB"mstr_symbols"
VOLTAGE"1.1V";
"G\NAC"6;
%"VCC_CORE"
"1","(2500,2725)","0","mstr_symbols","I25";
;
CDS_LIB"mstr_symbols"
HDL_POWER"PVCCIOMCP_CPU0";
"A"7;
%"VCC_CORE"
"1","(2500,3450)","0","mstr_symbols","I26";
;
CDS_LIB"mstr_symbols"
HDL_POWER"PVCCMCP_CPU0";
"A"8;
%"PVPP_ABC"
"1","(2325,2025)","0","mstr_symbols","I31";
;
HDL_POWER"PVPP_ABC"
ROOM"PVPP_KLM_VR"
BODY_TYPE"PLUMBING"
BOM_COST"PVPP_KLM_VR"
CDS_LIB"mstr_symbols"
VOLTAGE"2.5V";
"G\NAC"9;
%"SKX_EXT_B"
"20","(-1950,2650)","0","chpset_lib","I33";
;
CDS_SEC"20"
ROOM"CPU0"
CDS_LOCATION"U5D1"
SEC"20"
CDS_LIB"chpset_lib"
SEC_TYPE"BGA1"
PACK_TYPE"BGA1"
MATERIAL"IC"
PART_NUMBER"TBD"
LOCATION"U5D1";
"VCCD345<0>"
$PN"EF59"2;
"VCCD345<1>"
$PN"EF53"2;
"VCCD345<2>"
$PN"EF49"2;
"VCCD345<3>"
$PN"EC62"2;
"VCCD345<4>"
$PN"EC60"2;
"VCCD345<5>"
$PN"EC58"2;
"VCCD345<6>"
$PN"EC56"2;
"VCCD345<7>"
$PN"EC54"2;
"VCCD345<8>"
$PN"EC52"2;
"VCCD345<9>"
$PN"EC50"2;
"VCCD345<10>"
$PN"EC48"2;
"VCCD345<11>"
$PN"EC46"2;
"VCCD345<12>"
$PN"DU64"2;
"VCCD345<13>"
$PN"DU62"2;
"VCCD345<14>"
$PN"DU60"2;
"VCCD345<15>"
$PN"DU58"2;
"VCCD345<16>"
$PN"DU56"2;
"VCCD345<17>"
$PN"DU54"2;
"VCCD345<18>"
$PN"DU52"2;
"VCCD345<19>"
$PN"DU50"2;
"VCCD345<20>"
$PN"DU48"2;
"VCCD345<21>"
$PN"DU46"2;
"VCCD345<22>"
$PN"DL62"2;
"VCCD345<23>"
$PN"DL60"2;
"VCCD345<24>"
$PN"DL58"2;
"VCCD345<25>"
$PN"DL56"2;
"VCCD345<26>"
$PN"DL54"2;
"VCCD345<27>"
$PN"DL52"2;
"VCCD345<28>"
$PN"DL50"2;
"VCCD345<29>"
$PN"DL48"2;
"VCCD345<30>"
$PN"DL46"2;
"VCCD345<31>"
$PN"DJ64"2;
"VCCD345<32>"
$PN"DH63"2;
"VCCD345<33>"
$PN"DH61"2;
"VCCD345<34>"
$PN"DH59"2;
"VCCD345<35>"
$PN"DH57"2;
"VCCD345<36>"
$PN"DH55"2;
"VCCD345<37>"
$PN"DH53"2;
"VCCD345<38>"
$PN"DH51"2;
"VCCD345<39>"
$PN"DH49"2;
"VCCD345<40>"
$PN"DH47"2;
"VCCD345<41>"
$PN"DH45"2;
"VCCD345<42>"
$PN"DD45"2;
"VCCD345<43>"
$PN"DB63"2;
"VCCD345<44>"
$PN"DB61"2;
"VCCD345<45>"
$PN"DB59"2;
"VCCD345<46>"
$PN"DB57"2;
"VCCD345<47>"
$PN"DB55"2;
"VCCD345<48>"
$PN"DB53"2;
"VCCD345<49>"
$PN"EF45"2;
"VCCD345<50>"
$PN"EE44"2;
"VCCD012<0>"
$PN"B49"1;
"VCCD012<1>"
$PN"B53"1;
"VCCD012<2>"
$PN"B59"1;
"VCCD012<3>"
$PN"E46"1;
"VCCD012<4>"
$PN"E48"1;
"VCCD012<5>"
$PN"E50"1;
"VCCD012<6>"
$PN"E52"1;
"VCCD012<7>"
$PN"E54"1;
"VCCD012<8>"
$PN"E56"1;
"VCCD012<9>"
$PN"E58"1;
"VCCD012<10>"
$PN"E60"1;
"VCCD012<11>"
$PN"E62"1;
"VCCD012<12>"
$PN"E64"1;
"VCCD012<13>"
$PN"L46"1;
"VCCD012<14>"
$PN"L48"1;
"VCCD012<15>"
$PN"L50"1;
"VCCD012<16>"
$PN"L52"1;
"VCCD012<17>"
$PN"L54"1;
"VCCD012<18>"
$PN"L56"1;
"VCCD012<19>"
$PN"L58"1;
"VCCD012<20>"
$PN"L60"1;
"VCCD012<21>"
$PN"L62"1;
"VCCD012<22>"
$PN"N64"1;
"VCCD012<23>"
$PN"U46"1;
"VCCD012<24>"
$PN"U48"1;
"VCCD012<25>"
$PN"U50"1;
"VCCD012<26>"
$PN"U52"1;
"VCCD012<27>"
$PN"U54"1;
"VCCD012<28>"
$PN"U56"1;
"VCCD012<29>"
$PN"U58"1;
"VCCD012<30>"
$PN"U60"1;
"VCCD012<31>"
$PN"U62"1;
"VCCD012<32>"
$PN"W64"1;
"VCCD012<33>"
$PN"Y45"1;
"VCCD012<34>"
$PN"Y47"1;
"VCCD012<35>"
$PN"Y49"1;
"VCCD012<36>"
$PN"Y51"1;
"VCCD012<37>"
$PN"Y53"1;
"VCCD012<38>"
$PN"Y55"1;
"VCCD012<39>"
$PN"Y57"1;
"VCCD012<40>"
$PN"Y59"1;
"VCCD012<41>"
$PN"Y61"1;
"VCCD012<42>"
$PN"Y63"1;
"VCCD012<43>"
$PN"AD45"1;
"VCCD012<44>"
$PN"AF55"1;
"VCCD012<45>"
$PN"AF57"1;
"VCCD012<46>"
$PN"AF59"1;
"VCCD012<47>"
$PN"AF61"1;
"VCCD012<48>"
$PN"AF63"1;
"VCCD012<49>"
$PN"D45"1;
"VCCD012<50>"
$PN"C46"1;
"VCCD012<51>"
$PN"B47"1;
%"SKX_EXT_B"
"21","(1050,2725)","0","chpset_lib","I34";
;
CDS_SEC"21"
ROOM"CPU0"
CDS_LOCATION"U5D1"
SEC"21"
CDS_LIB"chpset_lib"
SEC_TYPE"BGA1"
PACK_TYPE"BGA1"
MATERIAL"IC"
PART_NUMBER"TBD"
LOCATION"U5D1";
"VCCSA<0>"
$PN"CJ66"6;
"VCCSA<1>"
$PN"CJ64"6;
"VCCSA<2>"
$PN"CH75"6;
"VCCSA<3>"
$PN"CH65"6;
"VCCSA<4>"
$PN"CG74"6;
"VCCSA<5>"
$PN"CG66"6;
"VCCSA<6>"
$PN"CG64"6;
"VCCSA<7>"
$PN"CF75"6;
"VCCSA<8>"
$PN"CF73"6;
"VCCSA<9>"
$PN"CF67"6;
"VCCSA<10>"
$PN"CF65"6;
"VCCSA<11>"
$PN"CE74"6;
"VCCSA<12>"
$PN"CE72"6;
"VCCSA<13>"
$PN"CE68"6;
"VCCSA<14>"
$PN"CE66"6;
"VCCSA<15>"
$PN"CE64"6;
"VCCSA<16>"
$PN"CD71"6;
"VCCSA<17>"
$PN"CD69"6;
"VCCSA<18>"
$PN"CD67"6;
"VCCSA<19>"
$PN"CD65"6;
"VCCSA<20>"
$PN"CC70"6;
"VCCSA<21>"
$PN"CC68"6;
"VCCSA<22>"
$PN"CC66"6;
"VCCSA<23>"
$PN"CB69"6;
"VCCSA<24>"
$PN"CB67"6;
"VCCSA<25>"
$PN"CB65"6;
"VCCIO<20>"
$PN"CM15"5;
"VCCIO<21>"
$PN"CL12"5;
"VCCIO<22>"
$PN"CK5"5;
"VCCIO<23>"
$PN"CV7"5;
"VCCIO<24>"
$PN"CH9"5;
"VCCIO<25>"
$PN"D7"5;
"VCCIO<26>"
$PN"CE18"5;
"VCCIO<27>"
$PN"CD9"5;
"VCCIO<28>"
$PN"CB17"5;
"VCCIO<29>"
$PN"CB13"5;
"VCCIO<30>"
$PN"BP25"3;
"VCCIO<31>"
$PN"BJ24"3;
"VCCIO<32>"
$PN"BF23"3;
"VCCIO<33>"
$PN"DA14"3;
"VCCIO<34>"
$PN"BB5"3;
"VCCIO<35>"
$PN"BA24"3;
"VCCIO<36>"
$PN"AY11"3;
"VCCIO<37>"
$PN"AW6"3;
"VCCIO<38>"
$PN"AT11"3;
"VCCIO<39>"
$PN"DD7"3;
"VCCIO<40>"
$PN"AN10"3;
"VCCIO<41>"
$PN"DF13"3;
"VCCIO<42>"
$PN"AH9"3;
"VCCIO<43>"
$PN"AC4"3;
"VCCIO<44>"
$PN"AC20"3;
"VCCIO<45>"
$PN"AA10"3;
"VCCIO<46>"
$PN"W6"3;
"VCCIO<47>"
$PN"W4"3;
"VCCIO<48>"
$PN"DF21"3;
"VCCIO<49>"
$PN"U14"3;
"VCCIO<50>"
$PN"T3"3;
"VCCIO<51>"
$PN"P5"3;
"VCCIO<52>"
$PN"M21"3;
"VCCIO<53>"
$PN"M11"3;
"VCCIO<54>"
$PN"DG8"3;
"VCCIO<55>"
$PN"DH7"3;
"VCCIO<56>"
$PN"L16"3;
"VCCIO<57>"
$PN"L14"3;
"VCCIO<58>"
$PN"J10"3;
"VCCIO<59>"
$PN"H13"3;
"VCCIO<60>"
$PN"DJ16"3;
"VCCIO<61>"
$PN"DM17"3;
"VCCIO<62>"
$PN"DN8"3;
"VCCIO<63>"
$PN"DP19"3;
"VCCIO<64>"
$PN"DR10"3;
"VCCIO<65>"
$PN"DR2"3;
"VCCIO<66>"
$PN"DU20"3;
"VCCIO<67>"
$PN"EA12"3;
"VCCIO<68>"
$PN"EB15"3;
"VCCIO<69>"
$PN"J2"3;
"VCCIO<70>"
$PN"K15"3;
"VCCIO<71>"
$PN"M7"3;
"VCCIO<72>"
$PN"M9"3;
"VCCIO<73>"
$PN"N18"3;
"VCCIO<74>"
$PN"W10"3;
"VCCIO<75>"
$PN"BC26"3;
"VCCIO<76>"
$PN"BB27"3;
"VCCIO<77>"
$PN"BA26"3;
"VCCIO<78>"
$PN"AY27"3;
"VCCIO<79>"
$PN"AW26"3;
"VCCIO<80>"
$PN"AV27"3;
"VCCIO<81>"
$PN"CF27"3;
"VCCIO<82>"
$PN"CD27"3;
"VCCIO<83>"
$PN"CC26"3;
"VCCIO<84>"
$PN"CJ28"3;
"VCCIO<85>"
$PN"CH27"3;
"VCCIO<86>"
$PN"BM27"3;
"VCCIO<87>"
$PN"BL26"3;
"VCCIO<88>"
$PN"BK27"3;
"VCCIO<89>"
$PN"BK25"3;
"VCCIO<90>"
$PN"BJ26"3;
"VCCIO<91>"
$PN"BH27"3;
"VCCIO<92>"
$PN"BH25"3;
"VCCIO<93>"
$PN"BG26"3;
"VCCIO<94>"
$PN"BF27"3;
"VCCIO<95>"
$PN"AE36"3;
"VCCIO<96>"
$PN"AD37"3;
"VCCIO<97>"
$PN"AC36"3;
"VCCIO<98>"
$PN"AF35"3;
"VCCIO<99>"
$PN"AD35"3;
"VCCIO<100>"
$PN"AE34"3;
"VCCIO<101>"
$PN"AG34"3;
"VCCIO<102>"
$PN"AM29"3;
"VCCIO<103>"
$PN"AL28"3;
"VCCIO<104>"
$PN"AR28"3;
"VCC33"
$PN"CY55"11;
"CD_VPP<0>"
$PN"B11"9;
"CD_VPP<1>"
$PN"A12"9;
"CD_VPP<2>"
$PN"A10"9;
"CD_VPP<3>"
$PN"A8"9;
"CD_VCC_CORE<0>"
$PN"BL14"8;
"CD_VCC_CORE<1>"
$PN"BK15"8;
"CD_VCC_CORE<2>"
$PN"BK13"8;
"CD_VCC_CORE<3>"
$PN"BJ14"8;
"CD_VCC_CORE<4>"
$PN"BJ12"8;
"CD_VCC_CORE<5>"
$PN"BH13"8;
"CD_VCC_CORE<6>"
$PN"BG14"8;
"CD_VCC_CORE<7>"
$PN"BG12"8;
"CD_VCC_CORE<8>"
$PN"BF13"8;
"CD_VCC_CORE<9>"
$PN"BF11"8;
"CD_VCC_CORE<10>"
$PN"BE14"8;
"CD_VCC_CORE<11>"
$PN"BE12"8;
"CD_VCC_CORE<12>"
$PN"BD13"8;
"CD_VCCP<0>"
$PN"BV15"7;
"CD_VCCP<1>"
$PN"BV13"7;
"CD_VCCP<2>"
$PN"BV11"7;
"CD_VCCP<3>"
$PN"BU14"7;
"CD_VCCP<4>"
$PN"BU12"7;
"CD_VCCP<5>"
$PN"BT15"7;
"CD_VCCP<6>"
$PN"BT13"7;
"CD_VCCP<7>"
$PN"BT11"7;
"CD_VCCP<8>"
$PN"BR14"7;
"CD_VCCP<9>"
$PN"BR12"7;
"CD_VCCP<10>"
$PN"BP15"7;
"CD_VCCP<11>"
$PN"BP13"7;
"CD_VCCP<12>"
$PN"BP11"7;
"CD_VCCP<13>"
$PN"BN14"7;
"CD_VCCP<14>"
$PN"BN12"7;
"CD_VCCP<15>"
$PN"BM11"7;
"CD_VCCIN<0>"
$PN"BT27"10;
"CD_VCCIN<1>"
$PN"BU26"10;
"CD_VCCIN<2>"
$PN"BV27"10;
"CD_VCCIN<3>"
$PN"BY27"10;
%"VCC_CORE"
"1","(3550,1600)","0","mstr_symbols","I35";
;
CDS_LIB"mstr_symbols"
VOLTAGE"+1.8V"
HDL_POWER"P1V8_MCP_CPU0";
"A"10;
%"P3V3_STBY"
"1","(2650,1350)","0","mstr_symbols","I36";
;
HDL_POWER"P3V3_STBY"
BODY_TYPE"PLUMBING"
SIZE"1B"
CDS_LIB"mstr_symbols"
VOLTAGE"3.3V";
"G\NAC"11;
END.
